G04*
G04 #@! TF.GenerationSoftware,Altium Limited,Altium Designer,23.0.1 (38)*
G04*
G04 Layer_Color=128*
%FSLAX44Y44*%
%MOMM*%
G71*
G04*
G04 #@! TF.SameCoordinates,9A23C038-B079-480F-8166-AFFB5740F5AE*
G04*
G04*
G04 #@! TF.FilePolarity,Positive*
G04*
G01*
G75*
%ADD49C,0.0508*%
D49*
X521350Y208039D02*
X524650D01*
X523000Y206389D02*
Y209689D01*
X521315Y242000D02*
X524615D01*
X522965Y240350D02*
Y243650D01*
X534350Y232691D02*
X537650D01*
X536000Y231041D02*
Y234341D01*
X240371Y254805D02*
X243371D01*
X241871Y253305D02*
Y256305D01*
X229791Y254805D02*
X232791D01*
X231291Y253305D02*
Y256305D01*
X219211Y254805D02*
X222211D01*
X220711Y253305D02*
Y256305D01*
X208631Y254805D02*
X211631D01*
X210131Y253305D02*
Y256305D01*
X198134Y253481D02*
X201134D01*
X199634Y251981D02*
Y254981D01*
X188660Y248771D02*
X191660D01*
X190160Y247271D02*
Y250271D01*
X180889Y241591D02*
X183890D01*
X182390Y240091D02*
Y243091D01*
X173408Y234110D02*
X176408D01*
X174908Y232610D02*
Y235610D01*
X165927Y226629D02*
X168927D01*
X167427Y225129D02*
Y228129D01*
X158446Y219147D02*
X161446D01*
X159946Y217647D02*
Y220647D01*
X150965Y211666D02*
X153965D01*
X152465Y210166D02*
Y213166D01*
X142533Y205276D02*
X145533D01*
X144033Y203776D02*
Y206776D01*
X132056Y203805D02*
X135056D01*
X133555Y202305D02*
Y205305D01*
X121475Y203805D02*
X124475D01*
X122976Y202305D02*
Y205305D01*
X110910Y204354D02*
X113910D01*
X112410Y202854D02*
Y205854D01*
X100344Y203805D02*
X103344D01*
X101844Y202305D02*
Y205305D01*
X89764Y203805D02*
X92764D01*
X91264Y202305D02*
Y205305D01*
X79184Y203805D02*
X82184D01*
X80684Y202305D02*
Y205305D01*
X68605Y203927D02*
X71605D01*
X70105Y202427D02*
Y205427D01*
X60647Y210899D02*
X63647D01*
X62147Y209399D02*
Y212399D01*
X50102Y210033D02*
X53102D01*
X51602Y208533D02*
Y211533D01*
X43397Y201849D02*
X46397D01*
X44897Y200349D02*
Y203349D01*
X44609Y191339D02*
X47609D01*
X46109Y189839D02*
Y192839D01*
X52998Y184892D02*
X55998D01*
X54498Y183392D02*
Y186392D01*
X63466Y186424D02*
X66466D01*
X64966Y184924D02*
Y187924D01*
X72334Y192195D02*
X75334D01*
X73834Y190695D02*
Y193695D01*
X82914Y192195D02*
X85914D01*
X84414Y190695D02*
Y193695D01*
X93494Y192195D02*
X96494D01*
X94994Y190695D02*
Y193695D01*
X114552Y192195D02*
X117552D01*
X116052Y190695D02*
Y193695D01*
X125132Y192195D02*
X128132D01*
X126632Y190695D02*
Y193695D01*
X135712Y192229D02*
X138712D01*
X137212Y190729D02*
Y193729D01*
X146087Y194300D02*
X149087D01*
X147587Y192801D02*
Y195800D01*
X155182Y199706D02*
X158182D01*
X156682Y198206D02*
Y201206D01*
X162783Y207065D02*
X165783D01*
X164283Y205565D02*
Y208565D01*
X170264Y214546D02*
X173264D01*
X171765Y213046D02*
Y216046D01*
X177746Y222027D02*
X180746D01*
X179246Y220527D02*
Y223527D01*
X185227Y229508D02*
X188227D01*
X186727Y228008D02*
Y231008D01*
X192708Y236989D02*
X195708D01*
X194208Y235490D02*
Y238489D01*
X201783Y242429D02*
X204783D01*
X203283Y240929D02*
Y243929D01*
X212335Y243195D02*
X215335D01*
X213835Y241695D02*
Y244695D01*
X222915Y243195D02*
X225915D01*
X224415Y241695D02*
Y244695D01*
X233495Y243195D02*
X236495D01*
X234995Y241695D02*
Y244695D01*
X253709Y245785D02*
X256709D01*
X255209Y244285D02*
Y247285D01*
X250862Y255974D02*
X253862D01*
X252362Y254474D02*
Y257474D01*
X173989Y128600D02*
X177291D01*
X175640Y126949D02*
Y130251D01*
X123189Y154000D02*
X126491D01*
X124840Y152349D02*
Y155651D01*
X148589Y103200D02*
X151891D01*
X150240Y101549D02*
Y104851D01*
X402378Y103411D02*
X405680D01*
X404029Y101760D02*
Y105062D01*
X453389Y128600D02*
X456691D01*
X455040Y126949D02*
Y130251D01*
X427989Y128600D02*
X431291D01*
X429640Y126949D02*
Y130251D01*
X402589Y128600D02*
X405891D01*
X404240Y126949D02*
Y130251D01*
X300989Y230200D02*
X304291D01*
X302640Y228549D02*
Y231851D01*
X631189Y255600D02*
X634491D01*
X632840Y253949D02*
Y257251D01*
X631189Y230200D02*
X634491D01*
X632840Y228549D02*
Y231851D01*
X631189Y204800D02*
X634491D01*
X632840Y203149D02*
Y206451D01*
X631189Y154000D02*
X634491D01*
X632840Y152349D02*
Y155651D01*
X631189Y52400D02*
X634491D01*
X632840Y50749D02*
Y54051D01*
X605789Y281000D02*
X609091D01*
X607440Y279349D02*
Y282651D01*
X605789Y255600D02*
X609091D01*
X607440Y253949D02*
Y257251D01*
X605789Y230200D02*
X609091D01*
X607440Y228549D02*
Y231851D01*
X605789Y179400D02*
X609091D01*
X607440Y177749D02*
Y181051D01*
X605789Y52400D02*
X609091D01*
X607440Y50749D02*
Y54051D01*
X605789Y27000D02*
X609091D01*
X607440Y25349D02*
Y28651D01*
X580389Y281000D02*
X583691D01*
X582040Y279349D02*
Y282651D01*
X580389Y255600D02*
X583691D01*
X582040Y253949D02*
Y257251D01*
X580389Y154000D02*
X583691D01*
X582040Y152349D02*
Y155651D01*
X580389Y52400D02*
X583691D01*
X582040Y50749D02*
Y54051D01*
X554989Y281000D02*
X558291D01*
X556640Y279349D02*
Y282651D01*
X554989Y255600D02*
X558291D01*
X556640Y253949D02*
Y257251D01*
X554989Y204800D02*
X558291D01*
X556640Y203149D02*
Y206451D01*
X554989Y179400D02*
X558291D01*
X556640Y177749D02*
Y181051D01*
X554989Y154000D02*
X558291D01*
X556640Y152349D02*
Y155651D01*
X554989Y52400D02*
X558291D01*
X556640Y50749D02*
Y54051D01*
X529589Y281000D02*
X532891D01*
X531240Y279349D02*
Y282651D01*
X529589Y255600D02*
X532891D01*
X531240Y253949D02*
Y257251D01*
X529589Y52400D02*
X532891D01*
X531240Y50749D02*
Y54051D01*
X504189Y281000D02*
X507491D01*
X505840Y279349D02*
Y282651D01*
X504189Y204800D02*
X507491D01*
X505840Y203149D02*
Y206451D01*
X504189Y179400D02*
X507491D01*
X505840Y177749D02*
Y181051D01*
X504189Y154000D02*
X507491D01*
X505840Y152349D02*
Y155651D01*
X504189Y128600D02*
X507491D01*
X505840Y126949D02*
Y130251D01*
X504189Y52400D02*
X507491D01*
X505840Y50749D02*
Y54051D01*
X478789Y281000D02*
X482091D01*
X480440Y279349D02*
Y282651D01*
X478789Y255600D02*
X482091D01*
X480440Y253949D02*
Y257251D01*
X478789Y204800D02*
X482091D01*
X480440Y203149D02*
Y206451D01*
X478789Y179400D02*
X482091D01*
X480440Y177749D02*
Y181051D01*
X478789Y154000D02*
X482091D01*
X480440Y152349D02*
Y155651D01*
X478789Y128600D02*
X482091D01*
X480440Y126949D02*
Y130251D01*
X478789Y103200D02*
X482091D01*
X480440Y101549D02*
Y104851D01*
X478789Y52400D02*
X482091D01*
X480440Y50749D02*
Y54051D01*
X453389Y281000D02*
X456691D01*
X455040Y279349D02*
Y282651D01*
X453389Y255600D02*
X456691D01*
X455040Y253949D02*
Y257251D01*
X453389Y179400D02*
X456691D01*
X455040Y177749D02*
Y181051D01*
X453389Y154000D02*
X456691D01*
X455040Y152349D02*
Y155651D01*
X453389Y52400D02*
X456691D01*
X455040Y50749D02*
Y54051D01*
X427989Y281000D02*
X431291D01*
X429640Y279349D02*
Y282651D01*
X427989Y255600D02*
X431291D01*
X429640Y253949D02*
Y257251D01*
X427989Y230200D02*
X431291D01*
X429640Y228549D02*
Y231851D01*
X427989Y154000D02*
X431291D01*
X429640Y152349D02*
Y155651D01*
X427989Y103200D02*
X431291D01*
X429640Y101549D02*
Y104851D01*
X427989Y77800D02*
X431291D01*
X429640Y76149D02*
Y79451D01*
X427989Y52400D02*
X431291D01*
X429640Y50749D02*
Y54051D01*
X402589Y281000D02*
X405891D01*
X404240Y279349D02*
Y282651D01*
X402589Y255600D02*
X405891D01*
X404240Y253949D02*
Y257251D01*
X402589Y230200D02*
X405891D01*
X404240Y228549D02*
Y231851D01*
X402589Y204800D02*
X405891D01*
X404240Y203149D02*
Y206451D01*
X402589Y77800D02*
X405891D01*
X404240Y76149D02*
Y79451D01*
X402589Y52400D02*
X405891D01*
X404240Y50749D02*
Y54051D01*
X377189Y281000D02*
X380491D01*
X378840Y279349D02*
Y282651D01*
X377189Y179400D02*
X380491D01*
X378840Y177749D02*
Y181051D01*
X377189Y52400D02*
X380491D01*
X378840Y50749D02*
Y54051D01*
X351789Y281000D02*
X355091D01*
X353440Y279349D02*
Y282651D01*
X351789Y255600D02*
X355091D01*
X353440Y253949D02*
Y257251D01*
X351789Y179400D02*
X355091D01*
X353440Y177749D02*
Y181051D01*
X351789Y154000D02*
X355091D01*
X353440Y152349D02*
Y155651D01*
X351789Y52400D02*
X355091D01*
X353440Y50749D02*
Y54051D01*
X326389Y281000D02*
X329691D01*
X328040Y279349D02*
Y282651D01*
X326389Y179400D02*
X329691D01*
X328040Y177749D02*
Y181051D01*
X326389Y154000D02*
X329691D01*
X328040Y152349D02*
Y155651D01*
X326389Y128600D02*
X329691D01*
X328040Y126949D02*
Y130251D01*
X326389Y52400D02*
X329691D01*
X328040Y50749D02*
Y54051D01*
X300989Y281000D02*
X304291D01*
X302640Y279349D02*
Y282651D01*
X300989Y179400D02*
X304291D01*
X302640Y177749D02*
Y181051D01*
X300989Y154000D02*
X304291D01*
X302640Y152349D02*
Y155651D01*
X300989Y128600D02*
X304291D01*
X302640Y126949D02*
Y130251D01*
X300989Y52400D02*
X304291D01*
X302640Y50749D02*
Y54051D01*
X275589Y281000D02*
X278891D01*
X277240Y279349D02*
Y282651D01*
X275589Y179400D02*
X278891D01*
X277240Y177749D02*
Y181051D01*
X275589Y154000D02*
X278891D01*
X277240Y152349D02*
Y155651D01*
X275589Y128600D02*
X278891D01*
X277240Y126949D02*
Y130251D01*
X275589Y77800D02*
X278891D01*
X277240Y76149D02*
Y79451D01*
X275589Y52400D02*
X278891D01*
X277240Y50749D02*
Y54051D01*
X250189Y281000D02*
X253491D01*
X251840Y279349D02*
Y282651D01*
X250189Y179400D02*
X253491D01*
X251840Y177749D02*
Y181051D01*
X250189Y154000D02*
X253491D01*
X251840Y152349D02*
Y155651D01*
X250189Y128600D02*
X253491D01*
X251840Y126949D02*
Y130251D01*
X250189Y52400D02*
X253491D01*
X251840Y50749D02*
Y54051D01*
X224789Y281000D02*
X228091D01*
X226440Y279349D02*
Y282651D01*
X224789Y230200D02*
X228091D01*
X226440Y228549D02*
Y231851D01*
X224789Y204800D02*
X228091D01*
X226440Y203149D02*
Y206451D01*
X224789Y179400D02*
X228091D01*
X226440Y177749D02*
Y181051D01*
X224789Y154000D02*
X228091D01*
X226440Y152349D02*
Y155651D01*
X224789Y128600D02*
X228091D01*
X226440Y126949D02*
Y130251D01*
X224789Y103200D02*
X228091D01*
X226440Y101549D02*
Y104851D01*
X224789Y27000D02*
X228091D01*
X226440Y25349D02*
Y28651D01*
X199389Y281000D02*
X202691D01*
X201040Y279349D02*
Y282651D01*
X199389Y230200D02*
X202691D01*
X201040Y228549D02*
Y231851D01*
X199389Y204800D02*
X202691D01*
X201040Y203149D02*
Y206451D01*
X199389Y179400D02*
X202691D01*
X201040Y177749D02*
Y181051D01*
X199389Y154000D02*
X202691D01*
X201040Y152349D02*
Y155651D01*
X199389Y128600D02*
X202691D01*
X201040Y126949D02*
Y130251D01*
X199389Y103200D02*
X202691D01*
X201040Y101549D02*
Y104851D01*
X199389Y52400D02*
X202691D01*
X201040Y50749D02*
Y54051D01*
X199389Y27000D02*
X202691D01*
X201040Y25349D02*
Y28651D01*
X173989Y281000D02*
X177291D01*
X175640Y279349D02*
Y282651D01*
X173989Y255600D02*
X177291D01*
X175640Y253949D02*
Y257251D01*
X173989Y204800D02*
X177291D01*
X175640Y203149D02*
Y206451D01*
X173989Y179400D02*
X177291D01*
X175640Y177749D02*
Y181051D01*
X173989Y154000D02*
X177291D01*
X175640Y152349D02*
Y155651D01*
X173989Y77800D02*
X177291D01*
X175640Y76149D02*
Y79451D01*
X173989Y52400D02*
X177291D01*
X175640Y50749D02*
Y54051D01*
X173989Y27000D02*
X177291D01*
X175640Y25349D02*
Y28651D01*
X148589Y281000D02*
X151891D01*
X150240Y279349D02*
Y282651D01*
X148589Y255600D02*
X151891D01*
X150240Y253949D02*
Y257251D01*
X148589Y230200D02*
X151891D01*
X150240Y228549D02*
Y231851D01*
X148589Y179400D02*
X151891D01*
X150240Y177749D02*
Y181051D01*
X148589Y154000D02*
X151891D01*
X150240Y152349D02*
Y155651D01*
X148589Y77800D02*
X151891D01*
X150240Y76149D02*
Y79451D01*
X148589Y52400D02*
X151891D01*
X150240Y50749D02*
Y54051D01*
X148589Y27000D02*
X151891D01*
X150240Y25349D02*
Y28651D01*
X123189Y281000D02*
X126491D01*
X124840Y279349D02*
Y282651D01*
X123189Y255600D02*
X126491D01*
X124840Y253949D02*
Y257251D01*
X123189Y230200D02*
X126491D01*
X124840Y228549D02*
Y231851D01*
X123189Y77800D02*
X126491D01*
X124840Y76149D02*
Y79451D01*
X123189Y52400D02*
X126491D01*
X124840Y50749D02*
Y54051D01*
X123189Y27000D02*
X126491D01*
X124840Y25349D02*
Y28651D01*
X97789Y281000D02*
X101091D01*
X99440Y279349D02*
Y282651D01*
X97789Y255600D02*
X101091D01*
X99440Y253949D02*
Y257251D01*
X97789Y154000D02*
X101091D01*
X99440Y152349D02*
Y155651D01*
X97789Y77800D02*
X101091D01*
X99440Y76149D02*
Y79451D01*
X97789Y52400D02*
X101091D01*
X99440Y50749D02*
Y54051D01*
X97789Y27000D02*
X101091D01*
X99440Y25349D02*
Y28651D01*
X72389Y281000D02*
X75691D01*
X74040Y279349D02*
Y282651D01*
X72389Y255600D02*
X75691D01*
X74040Y253949D02*
Y257251D01*
X72389Y230200D02*
X75691D01*
X74040Y228549D02*
Y231851D01*
X72389Y179400D02*
X75691D01*
X74040Y177749D02*
Y181051D01*
X72389Y154000D02*
X75691D01*
X74040Y152349D02*
Y155651D01*
X72389Y128600D02*
X75691D01*
X74040Y126949D02*
Y130251D01*
X72389Y103200D02*
X75691D01*
X74040Y101549D02*
Y104851D01*
X72389Y77800D02*
X75691D01*
X74040Y76149D02*
Y79451D01*
X72389Y52400D02*
X75691D01*
X74040Y50749D02*
Y54051D01*
X72389Y27000D02*
X75691D01*
X74040Y25349D02*
Y28651D01*
X46989Y255600D02*
X50291D01*
X48640Y253949D02*
Y257251D01*
X46989Y154000D02*
X50291D01*
X48640Y152349D02*
Y155651D01*
X46989Y128600D02*
X50291D01*
X48640Y126949D02*
Y130251D01*
X46989Y103200D02*
X50291D01*
X48640Y101549D02*
Y104851D01*
X46989Y77800D02*
X50291D01*
X48640Y76149D02*
Y79451D01*
X46989Y52400D02*
X50291D01*
X48640Y50749D02*
Y54051D01*
X21589Y255600D02*
X24891D01*
X23240Y253949D02*
Y257251D01*
X21589Y154000D02*
X24891D01*
X23240Y152349D02*
Y155651D01*
X21589Y128600D02*
X24891D01*
X23240Y126949D02*
Y130251D01*
X21589Y103200D02*
X24891D01*
X23240Y101549D02*
Y104851D01*
X21589Y77800D02*
X24891D01*
X23240Y76149D02*
Y79451D01*
X21589Y52400D02*
X24891D01*
X23240Y50749D02*
Y54051D01*
X534350Y208000D02*
X537650D01*
X536000Y206350D02*
Y209650D01*
X559350Y103000D02*
X562650D01*
X561000Y101350D02*
Y104650D01*
X559350Y123000D02*
X562650D01*
X561000Y121350D02*
Y124650D01*
X558350Y143000D02*
X561650D01*
X560000Y141350D02*
Y144650D01*
M02*
